#ISCELL
  mstr_symbols bom_note *
  *
#ISCELL
  mstr_symbols intel_corp_bpage *
  *
#ISCELL
  mstr_standard offpage *
  page49_i1
#ISCELL
  mstr_standard tap *
  page49_i10
#ISCELL
  mstr_standard tap *
  page49_i100
#ISCELL
  mstr_standard tap *
  page49_i101
#ISCELL
  mstr_standard tap *
  page49_i102
#ISCELL
  mstr_standard tap *
  page49_i103
#ISCELL
  mstr_standard tap *
  page49_i104
#ISCELL
  mstr_standard tap *
  page49_i105
#ISCELL
  mstr_standard tap *
  page49_i106
#ISCELL
  mstr_standard tap *
  page49_i107
#ISCELL
  mstr_standard tap *
  page49_i108
#ISCELL
  mstr_standard tap *
  page49_i109
#ISCELL
  mstr_standard tap *
  page49_i11
#ISCELL
  mstr_standard tap *
  page49_i110
#CELL
  mstr_sconn sconn288_h44441004 *
  page49_i111
#ISCELL
  mstr_standard tap *
  page49_i112
#ISCELL
  mstr_standard tap *
  page49_i113
#ISCELL
  mstr_standard tap *
  page49_i114
#ISCELL
  mstr_standard tap *
  page49_i115
#ISCELL
  mstr_standard tap *
  page49_i116
#ISCELL
  mstr_standard tap *
  page49_i117
#ISCELL
  mstr_standard tap *
  page49_i118
#ISCELL
  mstr_standard tap *
  page49_i119
#ISCELL
  mstr_standard tap *
  page49_i12
#ISCELL
  mstr_standard tap *
  page49_i120
#ISCELL
  mstr_standard tap *
  page49_i121
#ISCELL
  mstr_standard tap *
  page49_i122
#ISCELL
  mstr_standard tap *
  page49_i123
#ISCELL
  mstr_standard tap *
  page49_i124
#ISCELL
  mstr_standard tap *
  page49_i125
#ISCELL
  mstr_standard tap *
  page49_i126
#ISCELL
  mstr_standard tap *
  page49_i127
#ISCELL
  mstr_standard tap *
  page49_i128
#ISCELL
  mstr_standard tap *
  page49_i129
#ISCELL
  mstr_standard tap *
  page49_i13
#ISCELL
  mstr_standard tap *
  page49_i130
#ISCELL
  mstr_standard offpage *
  page49_i131
#ISCELL
  mstr_standard offpage *
  page49_i132
#ISCELL
  mstr_standard tap *
  page49_i133
#ISCELL
  mstr_standard tap *
  page49_i134
#ISCELL
  mstr_standard tap *
  page49_i135
#ISCELL
  mstr_standard offpage *
  page49_i136
#ISCELL
  mstr_standard offpage *
  page49_i137
#ISCELL
  mstr_standard tap *
  page49_i138
#ISCELL
  mstr_standard tap *
  page49_i139
#ISCELL
  mstr_standard tap *
  page49_i14
#ISCELL
  mstr_standard tap *
  page49_i140
#ISCELL
  mstr_standard tap *
  page49_i141
#ISCELL
  mstr_standard tap *
  page49_i142
#ISCELL
  mstr_standard tap *
  page49_i143
#ISCELL
  mstr_standard tap *
  page49_i144
#ISCELL
  mstr_standard tap *
  page49_i145
#ISCELL
  mstr_standard offpage *
  page49_i146
#ISCELL
  mstr_standard offpage *
  page49_i147
#ISCELL
  mstr_standard offpage *
  page49_i148
#ISCELL
  mstr_standard offpage *
  page49_i149
#ISCELL
  mstr_standard tap *
  page49_i15
#ISCELL
  mstr_standard offpage *
  page49_i150
#ISCELL
  mstr_standard offpage *
  page49_i151
#ISCELL
  mstr_standard tap *
  page49_i152
#ISCELL
  mstr_standard tap *
  page49_i153
#ISCELL
  mstr_standard tap *
  page49_i154
#ISCELL
  mstr_standard tap *
  page49_i155
#ISCELL
  mstr_standard offpage *
  page49_i156
#ISCELL
  mstr_standard offpage *
  page49_i157
#ISCELL
  mstr_standard tap *
  page49_i158
#ISCELL
  mstr_standard tap *
  page49_i159
#ISCELL
  mstr_symbols pvddq_def *
  page49_i16
#ISCELL
  mstr_standard tap *
  page49_i160
#ISCELL
  mstr_standard tap *
  page49_i161
#ISCELL
  mstr_standard tap *
  page49_i162
#ISCELL
  mstr_standard tap *
  page49_i163
#ISCELL
  mstr_standard offpage *
  page49_i164
#ISCELL
  mstr_standard offpage *
  page49_i165
#ISCELL
  mstr_standard offpage *
  page49_i166
#ISCELL
  mstr_standard tap *
  page49_i167
#ISCELL
  mstr_standard tap *
  page49_i168
#CELL
  mstr_sconn sconn288_h44441004 *
  page49_i169
#ISCELL
  mstr_symbols pvtt_def *
  page49_i170
#ISCELL
  mstr_symbols gnd *
  page49_i171
#ISCELL
  mstr_standard offpage *
  page49_i174
#ISCELL
  mstr_standard offpage *
  page49_i175
#ISCELL
  mstr_standard offpage *
  page49_i176
#ISCELL
  mstr_symbols gnd *
  page49_i178
#CELL
  dev_discrete cap_a *
  page49_i179
#ISCELL
  mstr_symbols gnd *
  page49_i180
#ISCELL
  mstr_symbols pvpp_def *
  page49_i181
#ISCELL
  mstr_symbols pvpp_def *
  page49_i182
#ISCELL
  mstr_standard offpage *
  page49_i183
#ISCELL
  mstr_symbols p12v_nvdimm_def *
  page49_i184
#ISCELL
  mstr_standard tap *
  page49_i19
#ISCELL
  mstr_standard offpage *
  page49_i2
#ISCELL
  mstr_standard tap *
  page49_i20
#ISCELL
  mstr_standard tap *
  page49_i21
#ISCELL
  mstr_standard tap *
  page49_i22
#ISCELL
  mstr_standard tap *
  page49_i23
#ISCELL
  mstr_standard tap *
  page49_i24
#ISCELL
  mstr_standard tap *
  page49_i25
#ISCELL
  mstr_standard tap *
  page49_i26
#ISCELL
  mstr_standard tap *
  page49_i27
#ISCELL
  mstr_standard tap *
  page49_i28
#ISCELL
  mstr_standard tap *
  page49_i29
#ISCELL
  mstr_standard tap *
  page49_i3
#ISCELL
  mstr_standard tap *
  page49_i30
#ISCELL
  mstr_standard tap *
  page49_i31
#ISCELL
  mstr_standard tap *
  page49_i32
#ISCELL
  mstr_standard tap *
  page49_i33
#ISCELL
  mstr_standard tap *
  page49_i34
#ISCELL
  mstr_standard tap *
  page49_i35
#ISCELL
  mstr_standard tap *
  page49_i36
#ISCELL
  mstr_standard tap *
  page49_i37
#ISCELL
  mstr_standard tap *
  page49_i38
#ISCELL
  mstr_standard tap *
  page49_i39
#ISCELL
  mstr_standard tap *
  page49_i4
#ISCELL
  mstr_standard tap *
  page49_i40
#ISCELL
  mstr_standard tap *
  page49_i41
#CELL
  mstr_sconn sconn288_h44441004 *
  page49_i43
#ISCELL
  mstr_symbols gnd *
  page49_i44
#ISCELL
  mstr_standard offpage *
  page49_i45
#ISCELL
  mstr_standard tap *
  page49_i46
#ISCELL
  mstr_standard tap *
  page49_i47
#ISCELL
  mstr_standard tap *
  page49_i48
#ISCELL
  mstr_standard tap *
  page49_i49
#ISCELL
  mstr_standard tap *
  page49_i5
#ISCELL
  mstr_standard tap *
  page49_i50
#ISCELL
  mstr_standard tap *
  page49_i51
#ISCELL
  mstr_standard tap *
  page49_i52
#ISCELL
  mstr_standard tap *
  page49_i53
#ISCELL
  mstr_standard tap *
  page49_i54
#ISCELL
  mstr_standard tap *
  page49_i55
#ISCELL
  mstr_standard tap *
  page49_i56
#ISCELL
  mstr_standard tap *
  page49_i57
#ISCELL
  mstr_standard tap *
  page49_i58
#ISCELL
  mstr_standard tap *
  page49_i59
#ISCELL
  mstr_standard tap *
  page49_i6
#ISCELL
  mstr_standard tap *
  page49_i60
#ISCELL
  mstr_standard tap *
  page49_i61
#ISCELL
  mstr_standard tap *
  page49_i62
#ISCELL
  mstr_standard tap *
  page49_i63
#ISCELL
  mstr_standard tap *
  page49_i64
#ISCELL
  mstr_standard tap *
  page49_i65
#CELL
  mstr_sconn sconn288_h44441004 *
  page49_i66
#ISCELL
  mstr_standard tap *
  page49_i67
#ISCELL
  mstr_standard tap *
  page49_i68
#ISCELL
  mstr_standard tap *
  page49_i69
#ISCELL
  mstr_standard tap *
  page49_i7
#ISCELL
  mstr_standard tap *
  page49_i70
#ISCELL
  mstr_standard tap *
  page49_i71
#ISCELL
  mstr_standard tap *
  page49_i72
#ISCELL
  mstr_standard tap *
  page49_i73
#ISCELL
  mstr_standard tap *
  page49_i74
#ISCELL
  mstr_standard tap *
  page49_i75
#ISCELL
  mstr_standard tap *
  page49_i76
#ISCELL
  mstr_standard tap *
  page49_i77
#ISCELL
  mstr_standard tap *
  page49_i78
#ISCELL
  mstr_standard tap *
  page49_i79
#ISCELL
  mstr_standard tap *
  page49_i8
#ISCELL
  mstr_standard tap *
  page49_i80
#ISCELL
  mstr_standard tap *
  page49_i81
#ISCELL
  mstr_standard tap *
  page49_i82
#ISCELL
  mstr_standard tap *
  page49_i83
#ISCELL
  mstr_standard tap *
  page49_i84
#ISCELL
  mstr_standard tap *
  page49_i85
#ISCELL
  mstr_standard tap *
  page49_i86
#ISCELL
  mstr_standard tap *
  page49_i87
#ISCELL
  mstr_standard tap *
  page49_i88
#ISCELL
  mstr_standard tap *
  page49_i89
#ISCELL
  mstr_standard tap *
  page49_i9
#ISCELL
  mstr_standard tap *
  page49_i90
#ISCELL
  mstr_standard tap *
  page49_i91
#ISCELL
  mstr_standard tap *
  page49_i92
#ISCELL
  mstr_standard tap *
  page49_i93
#ISCELL
  mstr_standard tap *
  page49_i94
#ISCELL
  mstr_standard tap *
  page49_i95
#ISCELL
  mstr_standard tap *
  page49_i96
#ISCELL
  mstr_standard tap *
  page49_i97
#ISCELL
  mstr_standard tap *
  page49_i98
#ISCELL
  mstr_standard tap *
  page49_i99
